(kicad_pcb
	(version 20241229)
	(generator "pcbnew")
	(generator_version "9.0")
	(general
		(thickness 1.711)
		(legacy_teardrops no)
	)
	(paper "A4")
	(title_block
		(title "Antmicro Baseboard for Jetson AGX Thor")
		(date "2026-02-18")
		(rev "1.1.0")
		(company "Antmicro Ltd")
		(comment 1 "www.antmicro.com")
		(comment 9 "footprints 408-412 of 1170")
	)
	(layers
		(0 "F.Cu" signal)
		(4 "In1.Cu" signal)
		(6 "In2.Cu" signal)
		(8 "In3.Cu" signal)
		(10 "In4.Cu" jumper)
		(12 "In5.Cu" signal)
		(14 "In6.Cu" signal)
		(16 "In7.Cu" signal)
		(18 "In8.Cu" signal)
		(2 "B.Cu" signal)
		(9 "F.Adhes" user "F.Adhesive")
		(11 "B.Adhes" user "B.Adhesive")
		(13 "F.Paste" user)
		(15 "B.Paste" user)
		(5 "F.SilkS" user "F.Silkscreen")
		(7 "B.SilkS" user "B.Silkscreen")
		(1 "F.Mask" user)
		(3 "B.Mask" user)
		(17 "Dwgs.User" user "User.Drawings")
		(19 "Cmts.User" user "User.Comments")
		(21 "Eco1.User" user "User.Eco1")
		(23 "Eco2.User" user "User.Eco2")
		(25 "Edge.Cuts" user)
		(27 "Margin" user)
		(31 "F.CrtYd" user "F.Courtyard")
		(29 "B.CrtYd" user "B.Courtyard")
		(35 "F.Fab" user)
		(33 "B.Fab" user)
	)
	(footprint "antmicro-footprints:TP_SMD_0.75mm"
		(layer "F.Cu")
		(at 177.5 57.1 90)
		(property "Reference" "TP98"
			(at -1.88 -0.51 90)
			(layer "F.SilkS")
			(hide yes)
			(effects
				(font
					(size 0.7 0.7)
					(thickness 0.15)
				)
				(justify left bottom)
			)
		)
		(property "Value" "TP_0.75mm_SMD"
			(at 0 1.2 90)
			(layer "F.Fab")
			(effects
				(font
					(size 0.7 0.7)
					(thickness 0.15)
				)
				(justify left bottom)
			)
		)
		(property "Description" "SMT test point"
			(at 0 0 90)
			(layer "F.Fab")
			(hide yes)
			(effects
				(font
					(size 1.27 1.27)
					(thickness 0.15)
				)
			)
		)
		(property "MPN" ""
			(at 0 0 90)
			(unlocked yes)
			(layer "F.Fab")
			(hide yes)
			(effects
				(font
					(size 1 1)
					(thickness 0.15)
				)
			)
		)
		(property "Manufacturer" ""
			(at 0 0 90)
			(unlocked yes)
			(layer "F.Fab")
			(hide yes)
			(effects
				(font
					(size 1 1)
					(thickness 0.15)
				)
			)
		)
		(property "Author" "Antmicro"
			(at 0 0 90)
			(unlocked yes)
			(layer "F.Fab")
			(hide yes)
			(effects
				(font
					(size 1 1)
					(thickness 0.15)
				)
			)
		)
		(property "License" "Apache-2.0"
			(at 0 0 90)
			(unlocked yes)
			(layer "F.Fab")
			(hide yes)
			(effects
				(font
					(size 1 1)
					(thickness 0.15)
				)
			)
		)
		(sheetname "/Power/")
		(sheetfile "power.kicad_sch")
		(attr exclude_from_pos_files exclude_from_bom)
		(fp_circle
			(center 0 0)
			(end 0.475 0)
			(stroke
				(width 0.05)
				(type default)
			)
			(fill no)
			(layer "F.CrtYd")
		)
		(fp_text user "License: Apache-2.0"
			(at -0.4 5.101 90)
			(layer "F.Fab")
			(effects
				(font
					(size 0.7 0.7)
					(thickness 0.15)
				)
				(justify left bottom)
			)
		)
		(fp_text user "Author: Antmicro"
			(at -0.4 3.901 90)
			(layer "F.Fab")
			(effects
				(font
					(size 0.7 0.7)
					(thickness 0.15)
				)
				(justify left bottom)
			)
		)
		(fp_text user "${REFERENCE}"
			(at -0.4 2.7 90)
			(layer "F.Fab")
			(effects
				(font
					(size 0.7 0.7)
					(thickness 0.15)
				)
				(justify left bottom)
			)
		)
		(pad "1" smd circle
			(at 0 0 90)
			(size 0.75 0.75)
			(layers "F.Cu" "F.Mask")
			(net 634 "+12V")
			(pinfunction "1")
			(pintype "passive")
		)
	)
	(footprint "antmicro-footprints:C_0805_2012Metric"
		(layer "F.Cu")
		(at 173.17 69.11 90)
		(descr "Capacitor SMD 0805")
		(tags "capacitor SMD 0805")
		(property "Reference" "C277"
			(at 1.91 0.739468 90)
			(layer "F.SilkS")
			(effects
				(font
					(size 0.7 0.7)
					(thickness 0.15)
				)
				(justify left bottom)
			)
		)
		(property "Value" "C_22u_25V_0805"
			(at -2.055717 1.963152 90)
			(layer "F.Fab")
			(effects
				(font
					(size 0.7 0.7)
					(thickness 0.15)
				)
				(justify left bottom)
			)
		)
		(property "Datasheet" "https://product.samsungsem.com/mlcc/CL21A226MAYNNN.do"
			(at 0 0 90)
			(layer "F.Fab")
			(hide yes)
			(effects
				(font
					(size 1.27 1.27)
					(thickness 0.15)
				)
			)
		)
		(property "Description" "SMT Multilayer Ceramic Capacitor, 22uF, +/-20%, 25V, X5R, 0805 [2012 Metric]"
			(at 0 0 90)
			(layer "F.Fab")
			(hide yes)
			(effects
				(font
					(size 1.27 1.27)
					(thickness 0.15)
				)
			)
		)
		(property "MPN" "CL21A226MAYNNNE"
			(at 0 0 90)
			(unlocked yes)
			(layer "F.Fab")
			(hide yes)
			(effects
				(font
					(size 1 1)
					(thickness 0.15)
				)
			)
		)
		(property "Manufacturer" "Samsung Electro-Mechanics"
			(at 0 0 90)
			(unlocked yes)
			(layer "F.Fab")
			(hide yes)
			(effects
				(font
					(size 1 1)
					(thickness 0.15)
				)
			)
		)
		(property "License" "Apache-2.0"
			(at 0 0 90)
			(unlocked yes)
			(layer "F.Fab")
			(hide yes)
			(effects
				(font
					(size 1 1)
					(thickness 0.15)
				)
			)
		)
		(property "Author" "Antmicro"
			(at 0 0 90)
			(unlocked yes)
			(layer "F.Fab")
			(hide yes)
			(effects
				(font
					(size 1 1)
					(thickness 0.15)
				)
			)
		)
		(property "Val" "22u"
			(at 0 0 90)
			(unlocked yes)
			(layer "F.Fab")
			(hide yes)
			(effects
				(font
					(size 1 1)
					(thickness 0.15)
				)
			)
		)
		(property "Voltage" "25V"
			(at 0 0 90)
			(unlocked yes)
			(layer "F.Fab")
			(hide yes)
			(effects
				(font
					(size 1 1)
					(thickness 0.15)
				)
			)
		)
		(property "Dielectric" "X5R"
			(at 0 0 90)
			(unlocked yes)
			(layer "F.Fab")
			(hide yes)
			(effects
				(font
					(size 1 1)
					(thickness 0.15)
				)
			)
		)
		(property "Public" "False"
			(at 0 0 90)
			(unlocked yes)
			(layer "F.Fab")
			(hide yes)
			(effects
				(font
					(size 1 1)
					(thickness 0.15)
				)
			)
		)
		(component_classes
			(class "DCDC_20V")
		)
		(sheetname "/DCDC/")
		(sheetfile "dcdc.kicad_sch")
		(attr smd)
		(fp_line
			(start -0.3 -0.7)
			(end 0.3 -0.7)
			(stroke
				(width 0.15)
				(type solid)
			)
			(layer "F.SilkS")
		)
		(fp_line
			(start -0.3 0.7)
			(end 0.3 0.7)
			(stroke
				(width 0.15)
				(type solid)
			)
			(layer "F.SilkS")
		)
		(fp_rect
			(start 1.95 -0.9)
			(end -1.95 0.9)
			(stroke
				(width 0.05)
				(type default)
			)
			(fill no)
			(layer "F.CrtYd")
		)
		(fp_rect
			(start -0.95 -0.675)
			(end 0.95 0.675)
			(stroke
				(width 0.15)
				(type solid)
			)
			(fill no)
			(layer "F.Fab")
		)
		(fp_text user "License: Apache-2.0"
			(at -1.9 4.947 90)
			(layer "F.Fab")
			(effects
				(font
					(size 0.7 0.7)
					(thickness 0.15)
				)
				(justify left bottom)
			)
		)
		(fp_text user "Author: Antmicro"
			(at -1.9 5.947 90)
			(layer "F.Fab")
			(effects
				(font
					(size 0.7 0.7)
					(thickness 0.15)
				)
				(justify left bottom)
			)
		)
		(fp_text user "${REFERENCE}"
			(at -1.9 3.947 90)
			(layer "F.Fab")
			(effects
				(font
					(size 0.7 0.7)
					(thickness 0.15)
				)
				(justify left bottom)
			)
		)
		(pad "1" smd roundrect
			(at -1.1 0 90)
			(size 1.2 1.3)
			(layers "F.Cu" "F.Mask" "F.Paste")
			(roundrect_rratio 0.25)
			(net 1 "GND")
			(pintype "passive")
		)
		(pad "2" smd roundrect
			(at 1.1 0 90)
			(size 1.2 1.3)
			(layers "F.Cu" "F.Mask" "F.Paste")
			(roundrect_rratio 0.25)
			(net 13 "VCC")
			(pintype "passive")
		)
	)
	(footprint "antmicro-footprints:C_0402_1005Metric"
		(layer "F.Cu")
		(at 195.2 79)
		(descr "Capacitor SMD 0402")
		(tags "capacitor SMD 0402")
		(property "Reference" "C120"
			(at -3.66 0.34 0)
			(layer "F.SilkS")
			(effects
				(font
					(size 0.7 0.7)
					(thickness 0.15)
				)
				(justify left bottom)
			)
		)
		(property "Value" "C_10u_0402"
			(at -1.022927 2.155213 0)
			(layer "F.Fab")
			(effects
				(font
					(size 0.7 0.7)
					(thickness 0.15)
				)
				(justify left bottom)
			)
		)
		(property "Datasheet" "https://www.yageo.com/en/Chart/Download/pdf/CC0402MRX5R5BB106"
			(at 0 0 0)
			(layer "F.Fab")
			(hide yes)
			(effects
				(font
					(size 1.27 1.27)
					(thickness 0.15)
				)
			)
		)
		(property "Description" "SMD Multilayer Ceramic Capacitor, 10 µF, 6.3 V, 0402 [1005 Metric], ± 20%, X5R, CC Series"
			(at 0 0 0)
			(layer "F.Fab")
			(hide yes)
			(effects
				(font
					(size 1.27 1.27)
					(thickness 0.15)
				)
			)
		)
		(property "MPN" "CC0402MRX5R5BB106"
			(at 0 0 0)
			(unlocked yes)
			(layer "F.Fab")
			(hide yes)
			(effects
				(font
					(size 1 1)
					(thickness 0.15)
				)
			)
		)
		(property "Manufacturer" "YAGEO"
			(at 0 0 0)
			(unlocked yes)
			(layer "F.Fab")
			(hide yes)
			(effects
				(font
					(size 1 1)
					(thickness 0.15)
				)
			)
		)
		(property "License" "Apache-2.0"
			(at 0 0 0)
			(unlocked yes)
			(layer "F.Fab")
			(hide yes)
			(effects
				(font
					(size 1 1)
					(thickness 0.15)
				)
			)
		)
		(property "Author" "Antmicro"
			(at 0 0 0)
			(unlocked yes)
			(layer "F.Fab")
			(hide yes)
			(effects
				(font
					(size 1 1)
					(thickness 0.15)
				)
			)
		)
		(property "Val" "10u"
			(at 0 0 0)
			(unlocked yes)
			(layer "F.Fab")
			(hide yes)
			(effects
				(font
					(size 1 1)
					(thickness 0.15)
				)
			)
		)
		(property "Voltage" ""
			(at 0 0 0)
			(unlocked yes)
			(layer "F.Fab")
			(hide yes)
			(effects
				(font
					(size 1 1)
					(thickness 0.15)
				)
			)
		)
		(property "Dielectric" ""
			(at 0 0 0)
			(unlocked yes)
			(layer "F.Fab")
			(hide yes)
			(effects
				(font
					(size 1 1)
					(thickness 0.15)
				)
			)
		)
		(sheetname "/USB Debug, PD/")
		(sheetfile "usb_debug_pd.kicad_sch")
		(attr smd)
		(fp_poly
			(pts
				(xy -0.925 -0.47) (xy 0.925 -0.47) (xy 0.925 0.47) (xy -0.925 0.47)
			)
			(stroke
				(width 0.05)
				(type default)
			)
			(fill no)
			(layer "F.CrtYd")
		)
		(fp_line
			(start -0.494 -0.25)
			(end 0.504 -0.25)
			(stroke
				(width 0.15)
				(type solid)
			)
			(layer "F.Fab")
		)
		(fp_line
			(start -0.494 0.248)
			(end -0.494 -0.25)
			(stroke
				(width 0.15)
				(type solid)
			)
			(layer "F.Fab")
		)
		(fp_line
			(start 0.504 -0.25)
			(end 0.504 0.248)
			(stroke
				(width 0.15)
				(type solid)
			)
			(layer "F.Fab")
		)
		(fp_line
			(start 0.504 0.248)
			(end -0.494 0.248)
			(stroke
				(width 0.15)
				(type solid)
			)
			(layer "F.Fab")
		)
		(fp_text user "License: Apache-2.0"
			(at -0.939 5.799 0)
			(layer "F.Fab")
			(effects
				(font
					(size 0.7 0.7)
					(thickness 0.15)
				)
				(justify left bottom)
			)
		)
		(fp_text user "Author: Antmicro"
			(at -0.939 3.399 0)
			(layer "F.Fab")
			(effects
				(font
					(size 0.7 0.7)
					(thickness 0.15)
				)
				(justify left bottom)
			)
		)
		(fp_text user "${REFERENCE}"
			(at -0.939 4.599 0)
			(layer "F.Fab")
			(effects
				(font
					(size 0.7 0.7)
					(thickness 0.15)
				)
				(justify left bottom)
			)
		)
		(pad "1" smd roundrect
			(at -0.48 0)
			(size 0.59 0.64)
			(layers "F.Cu" "F.Mask" "F.Paste")
			(roundrect_rratio 0.25)
			(net 1 "GND")
			(pintype "passive")
		)
		(pad "2" smd roundrect
			(at 0.48 0)
			(size 0.59 0.64)
			(layers "F.Cu" "F.Mask" "F.Paste")
			(roundrect_rratio 0.25)
			(net 293 "/USB Debug, PD/PDC_LDO_1V8")
			(pintype "passive")
		)
	)
	(footprint "antmicro-footprints:C_0402_1005Metric"
		(layer "F.Cu")
		(at 172.399468 119.226)
		(descr "Capacitor SMD 0402")
		(tags "capacitor SMD 0402")
		(property "Reference" "C383"
			(at -5.599468 0.374 0)
			(layer "F.SilkS")
			(effects
				(font
					(size 0.7 0.7)
					(thickness 0.15)
				)
				(justify left bottom)
			)
		)
		(property "Value" "C_100n_0402"
			(at -1.022927 2.155213 0)
			(layer "F.Fab")
			(effects
				(font
					(size 0.7 0.7)
					(thickness 0.15)
				)
				(justify left bottom)
			)
		)
		(property "Datasheet" "https://www.murata.com/products/productdetail?partno=GRM155R61H104KE14%23"
			(at 0 0 0)
			(layer "F.Fab")
			(hide yes)
			(effects
				(font
					(size 1.27 1.27)
					(thickness 0.15)
				)
			)
		)
		(property "Description" "SMD Multilayer Ceramic Capacitor, 0.1 µF, 50 V, 0402 [1005 Metric], ± 10%, X5R, GRM Series"
			(at 0 0 0)
			(layer "F.Fab")
			(hide yes)
			(effects
				(font
					(size 1.27 1.27)
					(thickness 0.15)
				)
			)
		)
		(property "Manufacturer" "Murata"
			(at 0 0 0)
			(unlocked yes)
			(layer "F.Fab")
			(hide yes)
			(effects
				(font
					(size 1 1)
					(thickness 0.15)
				)
			)
		)
		(property "MPN" "GRM155R61H104KE14D"
			(at 0 0 0)
			(unlocked yes)
			(layer "F.Fab")
			(hide yes)
			(effects
				(font
					(size 1 1)
					(thickness 0.15)
				)
			)
		)
		(property "Val" "100n"
			(at 0 0 0)
			(unlocked yes)
			(layer "F.Fab")
			(hide yes)
			(effects
				(font
					(size 1 1)
					(thickness 0.15)
				)
			)
		)
		(property "License" "Apache-2.0"
			(at 0 0 0)
			(unlocked yes)
			(layer "F.Fab")
			(hide yes)
			(effects
				(font
					(size 1 1)
					(thickness 0.15)
				)
			)
		)
		(property "Author" "Antmicro"
			(at 0 0 0)
			(unlocked yes)
			(layer "F.Fab")
			(hide yes)
			(effects
				(font
					(size 1 1)
					(thickness 0.15)
				)
			)
		)
		(property "Voltage" "50V"
			(at 0 0 0)
			(unlocked yes)
			(layer "F.Fab")
			(hide yes)
			(effects
				(font
					(size 1 1)
					(thickness 0.15)
				)
			)
		)
		(property "Dielectric" "X5R"
			(at 0 0 0)
			(unlocked yes)
			(layer "F.Fab")
			(hide yes)
			(effects
				(font
					(size 1 1)
					(thickness 0.15)
				)
			)
		)
		(sheetname "/DCDC/")
		(sheetfile "dcdc.kicad_sch")
		(attr smd)
		(fp_rect
			(start -0.925 -0.47)
			(end 0.925 0.47)
			(stroke
				(width 0.05)
				(type default)
			)
			(fill no)
			(layer "F.CrtYd")
		)
		(fp_line
			(start -0.494 -0.25)
			(end 0.504 -0.25)
			(stroke
				(width 0.15)
				(type solid)
			)
			(layer "F.Fab")
		)
		(fp_line
			(start -0.494 0.248)
			(end -0.494 -0.25)
			(stroke
				(width 0.15)
				(type solid)
			)
			(layer "F.Fab")
		)
		(fp_line
			(start 0.504 -0.25)
			(end 0.504 0.248)
			(stroke
				(width 0.15)
				(type solid)
			)
			(layer "F.Fab")
		)
		(fp_line
			(start 0.504 0.248)
			(end -0.494 0.248)
			(stroke
				(width 0.15)
				(type solid)
			)
			(layer "F.Fab")
		)
		(fp_text user "License: Apache-2.0"
			(at -0.939 5.799 0)
			(layer "F.Fab")
			(effects
				(font
					(size 0.7 0.7)
					(thickness 0.15)
				)
				(justify left bottom)
			)
		)
		(fp_text user "${REFERENCE}"
			(at -0.939 4.599 0)
			(layer "F.Fab")
			(effects
				(font
					(size 0.7 0.7)
					(thickness 0.15)
				)
				(justify left bottom)
			)
		)
		(fp_text user "Author: Antmicro"
			(at -0.939 3.399 0)
			(layer "F.Fab")
			(effects
				(font
					(size 0.7 0.7)
					(thickness 0.15)
				)
				(justify left bottom)
			)
		)
		(pad "1" smd roundrect
			(at -0.48 0)
			(size 0.59 0.64)
			(layers "F.Cu" "F.Mask" "F.Paste")
			(roundrect_rratio 0.25)
			(net 1161 "Net-(U50-IN-)")
			(pintype "passive")
		)
		(pad "2" smd roundrect
			(at 0.48 0)
			(size 0.59 0.64)
			(layers "F.Cu" "F.Mask" "F.Paste")
			(roundrect_rratio 0.25)
			(net 1281 "Net-(U50-IN+)")
			(pintype "passive")
		)
	)
	(footprint "antmicro-footprints:L_Bourns-SRP5030CA"
		(layer "F.Cu")
		(at 178.765 134.5 180)
		(property "Reference" "L2"
			(at -3.079468 2.13 90)
			(layer "F.SilkS")
			(effects
				(font
					(size 0.7 0.7)
					(thickness 0.15)
				)
				(justify right top)
			)
		)
		(property "Value" "L_560n_17.7A_Bourns-SRP5030CA"
			(at 0 4.241 0)
			(layer "F.Fab")
			(effects
				(font
					(size 0.7 0.7)
					(thickness 0.15)
				)
				(justify right top)
			)
		)
		(property "Datasheet" "https://www.bourns.com/docs/Product-Datasheets/SRP5030CA.pdf"
			(at 0 0 0)
			(layer "F.Fab")
			(hide yes)
			(effects
				(font
					(size 1.27 1.27)
					(thickness 0.15)
				)
			)
		)
		(property "Description" "Power Inductor (SMT), 560 nH, 17.7 A, Shielded, 22.2 A, SRP5030CA"
			(at 0 0 0)
			(layer "F.Fab")
			(hide yes)
			(effects
				(font
					(size 1.27 1.27)
					(thickness 0.15)
				)
			)
		)
		(property "Val" "560n/17.7A"
			(at 0 0 180)
			(unlocked yes)
			(layer "F.Fab")
			(hide yes)
			(effects
				(font
					(size 1 1)
					(thickness 0.15)
				)
			)
		)
		(property "Manufacturer" "Bourns"
			(at 0 0 180)
			(unlocked yes)
			(layer "F.Fab")
			(hide yes)
			(effects
				(font
					(size 1 1)
					(thickness 0.15)
				)
			)
		)
		(property "MPN" "SRP5030CA-R56M"
			(at 0 0 180)
			(unlocked yes)
			(layer "F.Fab")
			(hide yes)
			(effects
				(font
					(size 1 1)
					(thickness 0.15)
				)
			)
		)
		(property "ISat" "22.2 A"
			(at 0 0 180)
			(unlocked yes)
			(layer "F.Fab")
			(hide yes)
			(effects
				(font
					(size 1 1)
					(thickness 0.15)
				)
			)
		)
		(property "IMax" "17.7 A"
			(at 0 0 180)
			(unlocked yes)
			(layer "F.Fab")
			(hide yes)
			(effects
				(font
					(size 1 1)
					(thickness 0.15)
				)
			)
		)
		(property "Size" "5.5x5.3"
			(at 0 0 180)
			(unlocked yes)
			(layer "F.Fab")
			(hide yes)
			(effects
				(font
					(size 1 1)
					(thickness 0.15)
				)
			)
		)
		(property "Author" "Antmicro"
			(at 0 0 180)
			(unlocked yes)
			(layer "F.Fab")
			(hide yes)
			(effects
				(font
					(size 1 1)
					(thickness 0.15)
				)
			)
		)
		(property "License" "Apache-2.0"
			(at 0 0 180)
			(unlocked yes)
			(layer "F.Fab")
			(hide yes)
			(effects
				(font
					(size 1 1)
					(thickness 0.15)
				)
			)
		)
		(sheetname "/DCDC/")
		(sheetfile "dcdc.kicad_sch")
		(attr smd)
		(fp_line
			(start 2.65 2.75)
			(end 2.65 -2.75)
			(stroke
				(width 0.15)
				(type solid)
			)
			(layer "F.SilkS")
		)
		(fp_line
			(start -2.65 2.75)
			(end 2.65 2.75)
			(stroke
				(width 0.15)
				(type solid)
			)
			(layer "F.SilkS")
		)
		(fp_line
			(start -2.65 2.75)
			(end -2.65 -2.75)
			(stroke
				(width 0.15)
				(type solid)
			)
			(layer "F.SilkS")
		)
		(fp_line
			(start -2.65 -2.75)
			(end 2.65 -2.75)
			(stroke
				(width 0.15)
				(type solid)
			)
			(layer "F.SilkS")
		)
		(fp_rect
			(start -2.89 -2.99)
			(end 2.89 2.99)
			(stroke
				(width 0.05)
				(type solid)
			)
			(fill no)
			(layer "F.CrtYd")
		)
		(fp_line
			(start 2.65 2.75)
			(end -2.65 2.75)
			(stroke
				(width 0.15)
				(type solid)
			)
			(layer "F.Fab")
		)
		(fp_line
			(start 2.65 -2.75)
			(end 2.65 2.75)
			(stroke
				(width 0.15)
				(type solid)
			)
			(layer "F.Fab")
		)
		(fp_line
			(start -2.65 2.75)
			(end -2.65 -2.75)
			(stroke
				(width 0.15)
				(type solid)
			)
			(layer "F.Fab")
		)
		(fp_line
			(start -2.65 -2.75)
			(end 2.65 -2.75)
			(stroke
				(width 0.15)
				(type solid)
			)
			(layer "F.Fab")
		)
		(fp_text user "${REFERENCE}"
			(at -2.89 8.641 0)
			(layer "F.Fab")
			(effects
				(font
					(size 0.7 0.7)
					(thickness 0.15)
				)
				(justify right top)
			)
		)
		(fp_text user "Author: Antmicro"
			(at -2.89 7.441 0)
			(layer "F.Fab")
			(effects
				(font
					(size 0.7 0.7)
					(thickness 0.15)
				)
				(justify right top)
			)
		)
		(fp_text user "License: Apache-2.0"
			(at -2.89 6.241 0)
			(layer "F.Fab")
			(effects
				(font
					(size 0.7 0.7)
					(thickness 0.15)
				)
				(justify right top)
			)
		)
		(pad "1" smd roundrect
			(at -1.625 0 180)
			(size 1.25 4.7)
			(layers "F.Cu" "F.Mask" "F.Paste")
			(roundrect_rratio 0.1)
			(net 1182 "/DCDC/3V3_SW")
			(pintype "passive")
		)
		(pad "2" smd roundrect
			(at 1.625 0 180)
			(size 1.25 4.7)
			(layers "F.Cu" "F.Mask" "F.Paste")
			(roundrect_rratio 0.1)
			(net 567 "/DCDC/3V3_OUT")
			(pintype "passive")
		)
	)
)
